# BASEBOARD_FAB2 (Tioga Pass) — schematic netlist excerpt (pin names and nets, part order shuffled) for the footprints in the layout excerpt that follows; sources: Cadence DE-HDL packaged netlist, KiCad conversion of Wiwynn_Tioga_Pass_MB.brd

U1L5  TTL3126  74CBTLV3126 IC  pkg QFNLF  page 112
  OE(3)  = PWRGD_PVCCIN_CPU0
  A(3)  = XDP_OBSFN_B1_MBP7_N
  B(3)  = XDP_CPU_OBSFN_B1_MBP7_N
  OE(2)  = PWRGD_PVCCIN_CPU0
  A(2)  = XDP_OBSFN_B0_MBP6_N
  B(2)  = XDP_CPU_OBSFN_B0_MBP6_N
  B(1)  = XDP_CPU_PRDY_N
  A(1)  = XDP_PRDY_N
  OE(1)  = PWRGD_PVCCIN_CPU0
  B(0)  = XDP_CPU_PREQ_N
  A(0)  = XDP_PREQ_N
  OE(0)  = PWRGD_PVCCIN_CPU0

(kicad_pcb
	(version 20260206)
	(generator "pcbnew")
	(generator_version "10.0")
	(general
		(thickness 1.6)
		(legacy_teardrops no)
	)
	(paper "A4")
	(title_block
		(title "Wiwynn_Tioga_Pass_MB.brd")
		(comment 1 "Tioga Pass / footprints 4366-4366 of 4770")
	)
	(layers
		(0 "F.Cu" signal "TOP")
		(4 "In1.Cu" signal "L2GND")
		(6 "In2.Cu" signal "L3")
		(8 "In3.Cu" signal "L4GND")
		(10 "In4.Cu" signal "L5")
		(12 "In5.Cu" signal "L6GND")
		(14 "In6.Cu" signal "L7VCC")
		(16 "In7.Cu" signal "L8VCC")
		(18 "In8.Cu" signal "L9GND")
		(20 "In9.Cu" signal "L10")
		(22 "In10.Cu" signal "L11GND")
		(24 "In11.Cu" signal "L12")
		(26 "In12.Cu" signal "L13GND")
		(2 "B.Cu" signal "BOTTOM")
		(9 "F.Adhes" user "F.Adhesive")
		(11 "B.Adhes" user "B.Adhesive")
		(13 "F.Paste" user "Package Geometry/Pastemask Top")
		(15 "B.Paste" user "Package Geometry/Pastemask Bottom")
		(5 "F.SilkS" user "Ref Des/Silkscreen Top")
		(7 "B.SilkS" user "Ref Des/Silkscreen Bottom")
		(1 "F.Mask" user "Board Geometry/Soldermask Top")
		(3 "B.Mask" user "Board Geometry/Soldermask Bottom")
		(17 "Dwgs.User" user "User.Drawings")
		(19 "Cmts.User" user "User.Comments")
		(21 "Eco1.User" user "User.Eco1")
		(23 "Eco2.User" user "User.Eco2")
		(25 "Edge.Cuts" user "Board Geometry/Outline")
		(27 "Margin" user)
		(31 "F.CrtYd" user "Package Geometry/Place Bound Top")
		(29 "B.CrtYd" user "Package Geometry/Place Bound Bottom")
		(35 "F.Fab" user "Ref Des/Assembly Top")
		(33 "B.Fab" user "Ref Des/Assembly Bottom")
	)
	(footprint ""
		(layer "B.Cu")
		(at 459.753208 -136.144254 90)
		(property "Reference" "U1L5"
			(at 2.894076 -0.394208 0)
			(unlocked yes)
			(layer "B.SilkS")
			(effects
				(font
					(size 0.7874 0.5842)
					(thickness 0.1524)
				)
				(justify left mirror)
			)
		)
		(property "Value" ""
			(at 0 0 90)
			(layer "B.Fab")
			(effects
				(font
					(size 1.27 1.27)
				)
				(justify mirror)
			)
		)
		(duplicate_pad_numbers_are_jumpers no)
		(fp_circle
			(center 1.17856 -2.466086)
			(end 1.17856 -2.339086)
			(stroke
				(width 0.254)
				(type default)
			)
			(fill no)
			(layer "B.SilkS")
		)
		(fp_rect
			(start 0.9144 0.9144)
			(end -0.9144 -0.9144)
			(stroke
				(width 0)
				(type default)
			)
			(fill yes)
			(layer "B.Paste")
		)
		(fp_rect
			(start 1.82499 1.82499)
			(end -1.82499 -1.82499)
			(stroke
				(width 0)
				(type default)
			)
			(fill no)
			(layer "B.CrtYd")
		)
		(fp_line
			(start 1.82499 -1.82499)
			(end -1.82499 -1.82499)
			(stroke
				(width 0.1)
				(type default)
			)
			(layer "B.Fab")
		)
		(fp_line
			(start -1.82499 -1.82499)
			(end -1.82499 1.82499)
			(stroke
				(width 0.1)
				(type default)
			)
			(layer "B.Fab")
		)
		(fp_line
			(start 1.82499 1.82499)
			(end 1.82499 -1.82499)
			(stroke
				(width 0.1)
				(type default)
			)
			(layer "B.Fab")
		)
		(fp_line
			(start -1.82499 1.82499)
			(end 1.82499 1.82499)
			(stroke
				(width 0.1)
				(type default)
			)
			(layer "B.Fab")
		)
		(fp_circle
			(center 1.17856 -2.466086)
			(end 1.17856 -2.339086)
			(stroke
				(width 0.254)
				(type default)
			)
			(fill no)
			(layer "B.Fab")
		)
		(pad "1" smd custom
			(at 0.750062 -1.549908 270)
			(size 0.0762 0.0762)
			(layers "B.Cu" "B.Mask" "B.Paste")
			(net "PWRGD_PVCCIN_CPU0")
			(options
				(clearance outline)
				(anchor circle)
			)
			(primitives
				(gr_poly
					(pts
						(xy 0.1524 0.381)
						(arc
							(start 0.1524 -0.2286)
							(mid 0 -0.381)
							(end -0.1524 -0.2286)
						)
						(xy -0.1524 0.381)
					)
					(width 0)
					(fill yes)
				)
			)
		)
		(pad "2" smd custom
			(at 1.549908 -0.999998 270)
			(size 0.0762 0.0762)
			(layers "B.Cu" "B.Mask" "B.Paste")
			(net "XDP_OBSFN_B1_MBP7_N")
			(options
				(clearance outline)
				(anchor circle)
			)
			(primitives
				(gr_poly
					(pts
						(xy -0.381 0.1524)
						(arc
							(start 0.2286 0.1524)
							(mid 0.381 0)
							(end 0.2286 -0.1524)
						)
						(xy -0.381 -0.1524)
					)
					(width 0)
					(fill yes)
				)
			)
		)
		(pad "3" smd custom
			(at 1.549908 -0.500126 270)
			(size 0.0762 0.0762)
			(layers "B.Cu" "B.Mask" "B.Paste")
			(net "XDP_CPU_OBSFN_B1_MBP7_N")
			(options
				(clearance outline)
				(anchor circle)
			)
			(primitives
				(gr_poly
					(pts
						(xy -0.381 0.1524)
						(arc
							(start 0.2286 0.1524)
							(mid 0.381 0)
							(end 0.2286 -0.1524)
						)
						(xy -0.381 -0.1524)
					)
					(width 0)
					(fill yes)
				)
			)
		)
		(pad "4" smd custom
			(at 1.549908 0 270)
			(size 0.0762 0.0762)
			(layers "B.Cu" "B.Mask" "B.Paste")
			(net "PWRGD_PVCCIN_CPU0")
			(options
				(clearance outline)
				(anchor circle)
			)
			(primitives
				(gr_poly
					(pts
						(xy -0.381 0.1524)
						(arc
							(start 0.2286 0.1524)
							(mid 0.381 0)
							(end 0.2286 -0.1524)
						)
						(xy -0.381 -0.1524)
					)
					(width 0)
					(fill yes)
				)
			)
		)
		(pad "5" smd custom
			(at 1.549908 0.500126 270)
			(size 0.0762 0.0762)
			(layers "B.Cu" "B.Mask" "B.Paste")
			(net "XDP_OBSFN_B0_MBP6_N")
			(options
				(clearance outline)
				(anchor circle)
			)
			(primitives
				(gr_poly
					(pts
						(xy -0.381 0.1524)
						(arc
							(start 0.2286 0.1524)
							(mid 0.381 0)
							(end 0.2286 -0.1524)
						)
						(xy -0.381 -0.1524)
					)
					(width 0)
					(fill yes)
				)
			)
		)
		(pad "6" smd custom
			(at 1.549908 0.999998 270)
			(size 0.0762 0.0762)
			(layers "B.Cu" "B.Mask" "B.Paste")
			(net "XDP_CPU_OBSFN_B0_MBP6_N")
			(options
				(clearance outline)
				(anchor circle)
			)
			(primitives
				(gr_poly
					(pts
						(xy -0.381 0.1524)
						(arc
							(start 0.2286 0.1524)
							(mid 0.381 0)
							(end 0.2286 -0.1524)
						)
						(xy -0.381 -0.1524)
					)
					(width 0)
					(fill yes)
				)
			)
		)
		(pad "7" smd custom
			(at 0.750062 1.549908 270)
			(size 0.0762 0.0762)
			(layers "B.Cu" "B.Mask" "B.Paste")
			(net "GND")
			(options
				(clearance outline)
				(anchor circle)
			)
			(primitives
				(gr_poly
					(pts
						(xy -0.1524 -0.381)
						(arc
							(start -0.1524 0.2286)
							(mid 0 0.381)
							(end 0.1524 0.2286)
						)
						(xy 0.1524 -0.381)
					)
					(width 0)
					(fill yes)
				)
			)
		)
		(pad "8" smd custom
			(at -0.769874 1.549908 270)
			(size 0.0762 0.0762)
			(layers "B.Cu" "B.Mask" "B.Paste")
			(net "XDP_CPU_PRDY_N")
			(options
				(clearance outline)
				(anchor circle)
			)
			(primitives
				(gr_poly
					(pts
						(xy -0.1524 -0.381)
						(arc
							(start -0.1524 0.2286)
							(mid 0 0.381)
							(end 0.1524 0.2286)
						)
						(xy 0.1524 -0.381)
					)
					(width 0)
					(fill yes)
				)
			)
		)
		(pad "9" smd custom
			(at -1.549908 0.999998 270)
			(size 0.0762 0.0762)
			(layers "B.Cu" "B.Mask" "B.Paste")
			(net "XDP_PRDY_N")
			(options
				(clearance outline)
				(anchor circle)
			)
			(primitives
				(gr_poly
					(pts
						(xy 0.381 -0.1524)
						(arc
							(start -0.2286 -0.1524)
							(mid -0.381 0)
							(end -0.2286 0.1524)
						)
						(xy 0.381 0.1524)
					)
					(width 0)
					(fill yes)
				)
			)
		)
		(pad "10" smd custom
			(at -1.549908 0.500126 270)
			(size 0.0762 0.0762)
			(layers "B.Cu" "B.Mask" "B.Paste")
			(net "PWRGD_PVCCIN_CPU0")
			(options
				(clearance outline)
				(anchor circle)
			)
			(primitives
				(gr_poly
					(pts
						(xy 0.381 -0.1524)
						(arc
							(start -0.2286 -0.1524)
							(mid -0.381 0)
							(end -0.2286 0.1524)
						)
						(xy 0.381 0.1524)
					)
					(width 0)
					(fill yes)
				)
			)
		)
		(pad "11" smd custom
			(at -1.549908 0 270)
			(size 0.0762 0.0762)
			(layers "B.Cu" "B.Mask" "B.Paste")
			(net "XDP_CPU_PREQ_N")
			(options
				(clearance outline)
				(anchor circle)
			)
			(primitives
				(gr_poly
					(pts
						(xy 0.381 -0.1524)
						(arc
							(start -0.2286 -0.1524)
							(mid -0.381 0)
							(end -0.2286 0.1524)
						)
						(xy 0.381 0.1524)
					)
					(width 0)
					(fill yes)
				)
			)
		)
		(pad "12" smd custom
			(at -1.549908 -0.500126 270)
			(size 0.0762 0.0762)
			(layers "B.Cu" "B.Mask" "B.Paste")
			(net "XDP_PREQ_N")
			(options
				(clearance outline)
				(anchor circle)
			)
			(primitives
				(gr_poly
					(pts
						(xy 0.381 -0.1524)
						(arc
							(start -0.2286 -0.1524)
							(mid -0.381 0)
							(end -0.2286 0.1524)
						)
						(xy 0.381 0.1524)
					)
					(width 0)
					(fill yes)
				)
			)
		)
		(pad "13" smd custom
			(at -1.549908 -0.999998 270)
			(size 0.0762 0.0762)
			(layers "B.Cu" "B.Mask" "B.Paste")
			(net "PWRGD_PVCCIN_CPU0")
			(options
				(clearance outline)
				(anchor circle)
			)
			(primitives
				(gr_poly
					(pts
						(xy 0.381 -0.1524)
						(arc
							(start -0.2286 -0.1524)
							(mid -0.381 0)
							(end -0.2286 0.1524)
						)
						(xy 0.381 0.1524)
					)
					(width 0)
					(fill yes)
				)
			)
		)
		(pad "14" smd custom
			(at -0.750062 -1.549908 270)
			(size 0.0762 0.0762)
			(layers "B.Cu" "B.Mask" "B.Paste")
			(net "P3V3_STBY")
			(options
				(clearance outline)
				(anchor circle)
			)
			(primitives
				(gr_poly
					(pts
						(xy 0.1524 0.381)
						(arc
							(start 0.1524 -0.2286)
							(mid 0 -0.381)
							(end -0.1524 -0.2286)
						)
						(xy -0.1524 0.381)
					)
					(width 0)
					(fill yes)
				)
			)
		)
		(pad "15" smd rect
			(at 0 0 270)
			(size 1.8288 1.8288)
			(layers "B.Cu" "B.Mask" "B.Paste")
			(net "GND")
		)
	)
)
